(kicad_pcb
	(version 20241229)
	(generator "pcbnew")
	(generator_version "9.0")
	(general
		(thickness 1.294)
		(legacy_teardrops no)
	)
	(paper "A3")
	(title_block
		(title "Kintex 410T devboard")
		(date "2024-04-03")
		(rev "1.1.2")
		(comment 9 "footprints 408-412 of 975")
	)
	(layers
		(0 "F.Cu" mixed)
		(4 "In1.Cu" power)
		(6 "In2.Cu" power)
		(8 "In3.Cu" mixed)
		(10 "In4.Cu" power)
		(12 "In5.Cu" mixed)
		(14 "In6.Cu" power)
		(16 "In7.Cu" mixed)
		(18 "In8.Cu" power)
		(2 "B.Cu" mixed)
		(9 "F.Adhes" user "F.Adhesive")
		(11 "B.Adhes" user "B.Adhesive")
		(13 "F.Paste" user)
		(15 "B.Paste" user)
		(5 "F.SilkS" user "F.Silkscreen")
		(7 "B.SilkS" user "B.Silkscreen")
		(1 "F.Mask" user)
		(3 "B.Mask" user)
		(17 "Dwgs.User" user "User.Drawings")
		(19 "Cmts.User" user "User.Comments")
		(21 "Eco1.User" user "User.Eco1")
		(23 "Eco2.User" user "User.Eco2")
		(25 "Edge.Cuts" user)
		(27 "Margin" user)
		(31 "F.CrtYd" user "F.Courtyard")
		(29 "B.CrtYd" user "B.Courtyard")
		(35 "F.Fab" user)
		(33 "B.Fab" user)
	)
	(footprint "antmicro-footprints:WDFN-8-1EP_6x5mm_P1.27mm_EP3.4x4mm"
		(layer "F.Cu")
		(at 212.89 160.06 90)
		(property "Reference" "U13"
			(at -3.7 -3.2 90)
			(layer "F.SilkS")
			(effects
				(font
					(size 0.7 0.7)
					(thickness 0.15)
				)
				(justify left bottom)
			)
		)
		(property "Value" "MT25QL256ABA1EW7-0SIT"
			(at -10.1 4 90)
			(layer "F.Fab")
			(effects
				(font
					(size 0.7 0.7)
					(thickness 0.15)
				)
				(justify left bottom)
			)
		)
		(property "Description" "Flash Memory, Serial NOR, 256 Mbit, 32M x 8bit, SPI, MLP, 8 Pins"
			(at 0 0 90)
			(layer "F.Fab")
			(hide yes)
			(effects
				(font
					(size 1.27 1.27)
					(thickness 0.15)
				)
			)
		)
		(property "Author" "Antmicro"
			(at 372.95 -52.83 0)
			(layer "F.Fab")
			(hide yes)
			(effects
				(font
					(size 1 1)
					(thickness 0.15)
				)
			)
		)
		(property "DNP" "DNP"
			(at 372.95 -52.83 0)
			(layer "F.Fab")
			(hide yes)
			(effects
				(font
					(size 1 1)
					(thickness 0.15)
				)
			)
		)
		(property "License" "Apache-2.0"
			(at 372.95 -52.83 0)
			(layer "F.Fab")
			(hide yes)
			(effects
				(font
					(size 1 1)
					(thickness 0.15)
				)
			)
		)
		(property "MPN" "MT25QL256ABA1EW7-0SIT"
			(at 372.95 -52.83 0)
			(layer "F.Fab")
			(hide yes)
			(effects
				(font
					(size 1 1)
					(thickness 0.15)
				)
			)
		)
		(property "Manufacturer" "Micron Technology"
			(at 372.95 -52.83 0)
			(layer "F.Fab")
			(hide yes)
			(effects
				(font
					(size 1 1)
					(thickness 0.15)
				)
			)
		)
		(property "dnp" ""
			(at 372.95 -52.83 0)
			(layer "F.Fab")
			(hide yes)
			(effects
				(font
					(size 1 1)
					(thickness 0.15)
				)
			)
		)
		(property "exclude_from_bom" ""
			(at 372.95 -52.83 0)
			(layer "F.Fab")
			(hide yes)
			(effects
				(font
					(size 1 1)
					(thickness 0.15)
				)
			)
		)
		(sheetname "SPI Flash + SD Card")
		(sheetfile "spi-flash.kicad_sch")
		(attr smd exclude_from_bom)
		(fp_line
			(start -2.301 -2.601)
			(end 3.7 -2.601)
			(stroke
				(width 0.15)
				(type solid)
			)
			(layer "F.SilkS")
		)
		(fp_line
			(start -3.801 2.6)
			(end 3.7 2.6)
			(stroke
				(width 0.15)
				(type solid)
			)
			(layer "F.SilkS")
		)
		(fp_circle
			(center -3.3 -2.8)
			(end -3.25 -2.8)
			(stroke
				(width 0.15)
				(type solid)
			)
			(fill yes)
			(layer "F.SilkS")
		)
		(fp_rect
			(start -3.5 -3)
			(end 3.499 2.999)
			(stroke
				(width 0.05)
				(type solid)
			)
			(fill no)
			(layer "F.CrtYd")
		)
		(fp_line
			(start 2.999 -2.5)
			(end -2 -2.5)
			(stroke
				(width 0.15)
				(type solid)
			)
			(layer "F.Fab")
		)
		(fp_line
			(start -2 -2.5)
			(end -3 -1.5)
			(stroke
				(width 0.15)
				(type solid)
			)
			(layer "F.Fab")
		)
		(fp_line
			(start -3 -1.5)
			(end -3 2.499)
			(stroke
				(width 0.15)
				(type solid)
			)
			(layer "F.Fab")
		)
		(fp_line
			(start 2.999 2.499)
			(end 2.999 -2.5)
			(stroke
				(width 0.15)
				(type solid)
			)
			(layer "F.Fab")
		)
		(fp_line
			(start -3 2.499)
			(end 2.999 2.499)
			(stroke
				(width 0.15)
				(type solid)
			)
			(layer "F.Fab")
		)
		(pad "" smd roundrect
			(at -0.802 -1 90)
			(size 1.37 1.61)
			(layers "F.Paste")
			(roundrect_rratio 0.182482)
		)
		(pad "" smd roundrect
			(at -0.802 0.998 90)
			(size 1.37 1.61)
			(layers "F.Paste")
			(roundrect_rratio 0.182482)
		)
		(pad "" smd roundrect
			(at 0.8 -1 90)
			(size 1.37 1.61)
			(layers "F.Paste")
			(roundrect_rratio 0.182482)
		)
		(pad "" smd roundrect
			(at 0.8 0.998 90)
			(size 1.37 1.61)
			(layers "F.Paste")
			(roundrect_rratio 0.182482)
		)
		(pad "1" smd rect
			(at -3 -1.905 180)
			(size 0.5 1.5)
			(layers "F.Cu" "F.Mask" "F.Paste")
			(net 900 "/SPI Flash + SD Card/USR_FLASH_0_~{CS}")
			(pinfunction "~{CS}")
			(pintype "passive")
		)
		(pad "2" smd roundrect
			(at -3 -0.635 180)
			(size 0.5 1.5)
			(layers "F.Cu" "F.Mask" "F.Paste")
			(roundrect_rratio 0.25)
			(net 903 "/SPI Flash + SD Card/USR_FLASH_0_DQ1")
			(pinfunction "DQ1")
			(pintype "passive")
		)
		(pad "3" smd roundrect
			(at -3 0.633 180)
			(size 0.5 1.5)
			(layers "F.Cu" "F.Mask" "F.Paste")
			(roundrect_rratio 0.25)
			(net 904 "/SPI Flash + SD Card/USR_FLASH_0_DQ2")
			(pinfunction "DQ2/~{W}")
			(pintype "passive")
		)
		(pad "4" smd roundrect
			(at -3 1.904 180)
			(size 0.5 1.5)
			(layers "F.Cu" "F.Mask" "F.Paste")
			(roundrect_rratio 0.25)
			(net 1 "GND")
			(pinfunction "GND")
			(pintype "passive")
		)
		(pad "5" smd roundrect
			(at 2.999 1.904 180)
			(size 0.5 1.5)
			(layers "F.Cu" "F.Mask" "F.Paste")
			(roundrect_rratio 0.25)
			(net 902 "/SPI Flash + SD Card/USR_FLASH_0_DQ0")
			(pinfunction "DQ0")
			(pintype "passive")
		)
		(pad "6" smd roundrect
			(at 2.999 0.633 180)
			(size 0.5 1.5)
			(layers "F.Cu" "F.Mask" "F.Paste")
			(roundrect_rratio 0.25)
			(net 901 "/SPI Flash + SD Card/USR_FLASH_0_CLK")
			(pinfunction "CLK")
			(pintype "passive")
		)
		(pad "7" smd roundrect
			(at 2.999 -0.635 180)
			(size 0.5 1.5)
			(layers "F.Cu" "F.Mask" "F.Paste")
			(roundrect_rratio 0.25)
			(net 905 "/SPI Flash + SD Card/USR_FLASH_0_DQ3")
			(pinfunction "DQ3/~{HOLD}")
			(pintype "passive")
		)
		(pad "8" smd roundrect
			(at 2.999 -1.905 180)
			(size 0.5 1.5)
			(layers "F.Cu" "F.Mask" "F.Paste")
			(roundrect_rratio 0.25)
			(net 26 "+1V8")
			(pinfunction "VCC")
			(pintype "passive")
		)
		(pad "9" smd rect
			(at 0 0 90)
			(size 3.4 4)
			(layers "F.Cu" "F.Mask")
			(net 1 "GND")
			(pinfunction "EP")
			(pintype "passive")
			(solder_paste_margin -0.1)
		)
	)
	(footprint "antmicro-footprints:C_0402_1005Metric"
		(layer "F.Cu")
		(at 241.999 118.904)
		(descr "Capacitor SMD 0402")
		(tags "capacitor SMD 0402")
		(property "Reference" "C395"
			(at -1.899 1.246 0)
			(layer "F.SilkS")
			(effects
				(font
					(size 0.7 0.7)
					(thickness 0.15)
				)
				(justify left bottom)
			)
		)
		(property "Value" "C_100n_0402"
			(at 0 1.169 0)
			(layer "F.Fab")
			(effects
				(font
					(size 0.7 0.7)
					(thickness 0.15)
				)
				(justify left bottom)
			)
		)
		(property "Description" "SMD Multilayer Ceramic Capacitor, 0.1 µF, 50 V, 0402 [1005 Metric], ± 10%, X5R, GRM Series"
			(at 0 0 0)
			(layer "F.Fab")
			(hide yes)
			(effects
				(font
					(size 1.27 1.27)
					(thickness 0.15)
				)
			)
		)
		(property "Author" "Antmicro"
			(at 0 0 0)
			(layer "F.Fab")
			(hide yes)
			(effects
				(font
					(size 1 1)
					(thickness 0.15)
				)
			)
		)
		(property "Dielectric" "X5R"
			(at 0 0 0)
			(layer "F.Fab")
			(hide yes)
			(effects
				(font
					(size 1 1)
					(thickness 0.15)
				)
			)
		)
		(property "License" "Apache-2.0"
			(at 0 0 0)
			(layer "F.Fab")
			(hide yes)
			(effects
				(font
					(size 1 1)
					(thickness 0.15)
				)
			)
		)
		(property "MPN" "GRM155R61H104KE14D"
			(at 0 0 0)
			(layer "F.Fab")
			(hide yes)
			(effects
				(font
					(size 1 1)
					(thickness 0.15)
				)
			)
		)
		(property "Manufacturer" "Murata"
			(at 0 0 0)
			(layer "F.Fab")
			(hide yes)
			(effects
				(font
					(size 1 1)
					(thickness 0.15)
				)
			)
		)
		(property "Val" "100n"
			(at 0 0 0)
			(layer "F.Fab")
			(hide yes)
			(effects
				(font
					(size 1 1)
					(thickness 0.15)
				)
			)
		)
		(property "Voltage" "50V"
			(at 0 0 0)
			(layer "F.Fab")
			(hide yes)
			(effects
				(font
					(size 1 1)
					(thickness 0.15)
				)
			)
		)
		(sheetname "USB PHY")
		(sheetfile "usb-phy.kicad_sch")
		(attr smd)
		(fp_rect
			(start -0.925 -0.47)
			(end 0.925 0.47)
			(stroke
				(width 0.05)
				(type default)
			)
			(fill no)
			(layer "F.CrtYd")
		)
		(fp_line
			(start -0.494 -0.25)
			(end 0.504 -0.25)
			(stroke
				(width 0.15)
				(type solid)
			)
			(layer "F.Fab")
		)
		(fp_line
			(start -0.494 0.248)
			(end -0.494 -0.25)
			(stroke
				(width 0.15)
				(type solid)
			)
			(layer "F.Fab")
		)
		(fp_line
			(start 0.504 -0.25)
			(end 0.504 0.248)
			(stroke
				(width 0.15)
				(type solid)
			)
			(layer "F.Fab")
		)
		(fp_line
			(start 0.504 0.248)
			(end -0.494 0.248)
			(stroke
				(width 0.15)
				(type solid)
			)
			(layer "F.Fab")
		)
		(pad "1" smd roundrect
			(at -0.48 0)
			(size 0.59 0.64)
			(layers "F.Cu" "F.Mask" "F.Paste")
			(roundrect_rratio 0.25)
			(net 1 "GND")
			(pintype "passive")
		)
		(pad "2" smd roundrect
			(at 0.48 0)
			(size 0.59 0.64)
			(layers "F.Cu" "F.Mask" "F.Paste")
			(roundrect_rratio 0.25)
			(net 703 "+5V")
			(pintype "passive")
		)
	)
	(footprint "antmicro-footprints:C_0805_2012Metric"
		(layer "F.Cu")
		(at 176.05 178.1125)
		(descr "Capacitor SMD 0805")
		(tags "capacitor SMD 0805")
		(property "Reference" "C317"
			(at -1.3 2.8375 0)
			(layer "F.SilkS")
			(effects
				(font
					(size 0.7 0.7)
					(thickness 0.15)
				)
				(justify left bottom)
			)
		)
		(property "Value" "C_22u_25V_0805"
			(at 0 1.947 0)
			(layer "F.Fab")
			(effects
				(font
					(size 0.7 0.7)
					(thickness 0.15)
				)
				(justify left bottom)
			)
		)
		(property "Description" "SMT Multilayer Ceramic Capacitor, 22uF, +/-20%, 25V, X5R, 0805 [2012 Metric]"
			(at 0 0 0)
			(layer "F.Fab")
			(hide yes)
			(effects
				(font
					(size 1.27 1.27)
					(thickness 0.15)
				)
			)
		)
		(property "Author" "Antmicro"
			(at 0 0 0)
			(layer "F.Fab")
			(hide yes)
			(effects
				(font
					(size 1 1)
					(thickness 0.15)
				)
			)
		)
		(property "Dielectric" "X5R"
			(at 0 0 0)
			(layer "F.Fab")
			(hide yes)
			(effects
				(font
					(size 1 1)
					(thickness 0.15)
				)
			)
		)
		(property "License" "Apache-2.0"
			(at 0 0 0)
			(layer "F.Fab")
			(hide yes)
			(effects
				(font
					(size 1 1)
					(thickness 0.15)
				)
			)
		)
		(property "MPN" "CL21A226MAYNNNE"
			(at 0 0 0)
			(layer "F.Fab")
			(hide yes)
			(effects
				(font
					(size 1 1)
					(thickness 0.15)
				)
			)
		)
		(property "Manufacturer" "Samsung Electro-Mechanics"
			(at 0 0 0)
			(layer "F.Fab")
			(hide yes)
			(effects
				(font
					(size 1 1)
					(thickness 0.15)
				)
			)
		)
		(property "Val" "22u"
			(at 0 0 0)
			(layer "F.Fab")
			(hide yes)
			(effects
				(font
					(size 1 1)
					(thickness 0.15)
				)
			)
		)
		(property "Voltage" "25V"
			(at 0 0 0)
			(layer "F.Fab")
			(hide yes)
			(effects
				(font
					(size 1 1)
					(thickness 0.15)
				)
			)
		)
		(sheetname "DC-DC Converters")
		(sheetfile "dc-dc.kicad_sch")
		(attr smd)
		(fp_line
			(start -0.3 -0.7)
			(end 0.3 -0.7)
			(stroke
				(width 0.15)
				(type solid)
			)
			(layer "F.SilkS")
		)
		(fp_line
			(start -0.3 0.7)
			(end 0.3 0.7)
			(stroke
				(width 0.15)
				(type solid)
			)
			(layer "F.SilkS")
		)
		(fp_rect
			(start 1.95 -0.9)
			(end -1.95 0.9)
			(stroke
				(width 0.05)
				(type default)
			)
			(fill no)
			(layer "F.CrtYd")
		)
		(fp_rect
			(start -0.95 -0.675)
			(end 0.95 0.675)
			(stroke
				(width 0.15)
				(type solid)
			)
			(fill no)
			(layer "F.Fab")
		)
		(pad "1" smd roundrect
			(at -1.1 0)
			(size 1.2 1.3)
			(layers "F.Cu" "F.Mask" "F.Paste")
			(roundrect_rratio 0.25)
			(net 1 "GND")
			(pintype "passive")
		)
		(pad "2" smd roundrect
			(at 1.1 0)
			(size 1.2 1.3)
			(layers "F.Cu" "F.Mask" "F.Paste")
			(roundrect_rratio 0.25)
			(net 702 "VDC")
			(pintype "passive")
		)
	)
	(footprint "antmicro-footprints:NetTie-2_SMD_Pad0.127mm"
		(layer "F.Cu")
		(at 158.5 185.01 -90)
		(descr "Net tie, 2 pin, 0.127mm  SMD pads")
		(tags "net tie")
		(property "Reference" "NT39"
			(at -0.128 -1.345 270)
			(layer "F.SilkS")
			(hide yes)
			(effects
				(font
					(size 0.7 0.7)
					(thickness 0.15)
				)
				(justify left bottom)
			)
		)
		(property "Value" "Net-Tie_2"
			(at 0 1.199 270)
			(layer "F.Fab")
			(effects
				(font
					(size 0.7 0.7)
					(thickness 0.15)
				)
				(justify left bottom)
			)
		)
		(property "Description" "Net tie, 2 pins"
			(at 0 0 270)
			(layer "F.Fab")
			(hide yes)
			(effects
				(font
					(size 1.27 1.27)
					(thickness 0.15)
				)
			)
		)
		(property "Author" "Antmicro"
			(at -26.51 343.51 0)
			(layer "F.Fab")
			(hide yes)
			(effects
				(font
					(size 1 1)
					(thickness 0.15)
				)
			)
		)
		(property "License" "Apache-2.0"
			(at -26.51 343.51 0)
			(layer "F.Fab")
			(hide yes)
			(effects
				(font
					(size 1 1)
					(thickness 0.15)
				)
			)
		)
		(property "MPN" ""
			(at -26.51 343.51 0)
			(layer "F.Fab")
			(hide yes)
			(effects
				(font
					(size 1 1)
					(thickness 0.15)
				)
			)
		)
		(property "Manufacturer" ""
			(at -26.51 343.51 0)
			(layer "F.Fab")
			(hide yes)
			(effects
				(font
					(size 1 1)
					(thickness 0.15)
				)
			)
		)
		(sheetname "DC-DC Converters")
		(sheetfile "dc-dc.kicad_sch")
		(attr exclude_from_pos_files)
		(net_tie_pad_groups "1, 2")
		(fp_poly
			(pts
				(xy -0.0635 -0.0635) (xy 0.0625 -0.0635) (xy 0.0625 0.0635) (xy -0.0635 0.0635)
			)
			(stroke
				(width 0)
				(type solid)
			)
			(fill yes)
			(layer "F.Cu")
		)
		(pad "1" smd roundrect
			(at -0.127 0 90)
			(size 0.127 0.127)
			(layers "F.Cu")
			(roundrect_rratio 0.5)
			(chamfer_ratio 0)
			(chamfer top_left bottom_left)
			(net 279 "/DC-DC Converters/PB_CTRL.~{PB_CTRL_CLR}")
			(pinfunction "1")
			(pintype "passive")
		)
		(pad "2" smd roundrect
			(at 0.126 0 270)
			(size 0.127 0.127)
			(layers "F.Cu")
			(roundrect_rratio 0.5)
			(chamfer_ratio 0)
			(chamfer top_left bottom_left)
			(net 1340 "/SUP_MCU.SW_STATE")
			(pinfunction "2")
			(pintype "passive")
		)
	)
	(footprint "antmicro-footprints:C_0402_1005Metric"
		(layer "F.Cu")
		(at 239.41 148.16 180)
		(descr "Capacitor SMD 0402")
		(tags "capacitor SMD 0402")
		(property "Reference" "C249"
			(at 0.91 -2.24 180)
			(layer "F.SilkS")
			(effects
				(font
					(size 0.7 0.7)
					(thickness 0.15)
				)
				(justify left bottom)
			)
		)
		(property "Value" "C_100n_0402"
			(at 0 1.169 180)
			(layer "F.Fab")
			(effects
				(font
					(size 0.7 0.7)
					(thickness 0.15)
				)
				(justify left bottom)
			)
		)
		(property "Description" "SMD Multilayer Ceramic Capacitor, 0.1 µF, 50 V, 0402 [1005 Metric], ± 10%, X5R, GRM Series"
			(at 0 0 180)
			(layer "F.Fab")
			(hide yes)
			(effects
				(font
					(size 1.27 1.27)
					(thickness 0.15)
				)
			)
		)
		(property "Author" "Antmicro"
			(at 478.82 296.32 0)
			(layer "F.Fab")
			(hide yes)
			(effects
				(font
					(size 1 1)
					(thickness 0.15)
				)
			)
		)
		(property "Dielectric" "X5R"
			(at 478.82 296.32 0)
			(layer "F.Fab")
			(hide yes)
			(effects
				(font
					(size 1 1)
					(thickness 0.15)
				)
			)
		)
		(property "License" "Apache-2.0"
			(at 478.82 296.32 0)
			(layer "F.Fab")
			(hide yes)
			(effects
				(font
					(size 1 1)
					(thickness 0.15)
				)
			)
		)
		(property "MPN" "GRM155R61H104KE14D"
			(at 478.82 296.32 0)
			(layer "F.Fab")
			(hide yes)
			(effects
				(font
					(size 1 1)
					(thickness 0.15)
				)
			)
		)
		(property "Manufacturer" "Murata"
			(at 478.82 296.32 0)
			(layer "F.Fab")
			(hide yes)
			(effects
				(font
					(size 1 1)
					(thickness 0.15)
				)
			)
		)
		(property "Val" "100n"
			(at 478.82 296.32 0)
			(layer "F.Fab")
			(hide yes)
			(effects
				(font
					(size 1 1)
					(thickness 0.15)
				)
			)
		)
		(property "Voltage" "50V"
			(at 478.82 296.32 0)
			(layer "F.Fab")
			(hide yes)
			(effects
				(font
					(size 1 1)
					(thickness 0.15)
				)
			)
		)
		(sheetname "USB PHY")
		(sheetfile "usb-phy.kicad_sch")
		(attr smd)
		(fp_rect
			(start -0.925 -0.47)
			(end 0.925 0.47)
			(stroke
				(width 0.05)
				(type default)
			)
			(fill no)
			(layer "F.CrtYd")
		)
		(fp_line
			(start 0.504 0.248)
			(end -0.494 0.248)
			(stroke
				(width 0.15)
				(type solid)
			)
			(layer "F.Fab")
		)
		(fp_line
			(start 0.504 -0.25)
			(end 0.504 0.248)
			(stroke
				(width 0.15)
				(type solid)
			)
			(layer "F.Fab")
		)
		(fp_line
			(start -0.494 0.248)
			(end -0.494 -0.25)
			(stroke
				(width 0.15)
				(type solid)
			)
			(layer "F.Fab")
		)
		(fp_line
			(start -0.494 -0.25)
			(end 0.504 -0.25)
			(stroke
				(width 0.15)
				(type solid)
			)
			(layer "F.Fab")
		)
		(pad "1" smd roundrect
			(at -0.48 0 180)
			(size 0.59 0.64)
			(layers "F.Cu" "F.Mask" "F.Paste")
			(roundrect_rratio 0.25)
			(net 1 "GND")
			(pintype "passive")
		)
		(pad "2" smd roundrect
			(at 0.48 0 180)
			(size 0.59 0.64)
			(layers "F.Cu" "F.Mask" "F.Paste")
			(roundrect_rratio 0.25)
			(net 24 "+3V3")
			(pintype "passive")
		)
	)
)
